(kicad_pcb
	(version 20260206)
	(generator "pcbnew")
	(generator_version "10.0")
	(general
		(thickness 1.6)
		(legacy_teardrops no)
	)
	(paper "A4")
	(title_block
		(title "12092022_DA0F0TMDCD0_F0T_Management_Board_D_brd_V3_OCP.brd")
		(comment 1 "Grand Teton / footprints 868-872 of 1440")
	)
	(layers
		(0 "F.Cu" signal "TOP")
		(4 "In1.Cu" signal "GND")
		(6 "In2.Cu" signal "IN1")
		(8 "In3.Cu" signal "GND1")
		(10 "In4.Cu" signal "IN2")
		(12 "In5.Cu" signal "VCC")
		(14 "In6.Cu" signal "VCC1")
		(16 "In7.Cu" signal "IN3")
		(18 "In8.Cu" signal "GND2")
		(20 "In9.Cu" signal "IN4")
		(22 "In10.Cu" signal "GND3")
		(2 "B.Cu" signal "BOTTOM")
		(9 "F.Adhes" user "F.Adhesive")
		(11 "B.Adhes" user "B.Adhesive")
		(13 "F.Paste" user "Package Geometry/Pastemask Top")
		(15 "B.Paste" user "Package Geometry/Pastemask Bottom")
		(5 "F.SilkS" user "Ref Des/Silkscreen Top")
		(7 "B.SilkS" user "Ref Des/Silkscreen Bottom")
		(1 "F.Mask" user "Board Geometry/Soldermask Top")
		(3 "B.Mask" user "Board Geometry/Soldermask Bottom")
		(17 "Dwgs.User" user "User.Drawings")
		(19 "Cmts.User" user "User.Comments")
		(21 "Eco1.User" user "User.Eco1")
		(23 "Eco2.User" user "User.Eco2")
		(25 "Edge.Cuts" user "Board Geometry/Outline")
		(27 "Margin" user)
		(31 "F.CrtYd" user "Package Geometry/Place Bound Top")
		(29 "B.CrtYd" user "Package Geometry/Place Bound Bottom")
		(35 "F.Fab" user "Ref Des/Assembly Top")
		(33 "B.Fab" user "Ref Des/Assembly Bottom")
	)
	(footprint ""
		(layer "B.Cu")
		(at 95.911416 112.766602 -90)
		(property "Reference" "J29"
			(at 6.105398 -1.470914 270)
			(unlocked yes)
			(layer "B.SilkS")
			(effects
				(font
					(size 0.7874 0.5842)
					(thickness 0.1524)
				)
				(justify left mirror)
			)
		)
		(property "Value" ""
			(at 0 0 90)
			(layer "B.Fab")
			(effects
				(font
					(size 1.27 1.27)
				)
				(justify mirror)
			)
		)
		(duplicate_pad_numbers_are_jumpers no)
		(fp_line
			(start -1.2192 2.1082)
			(end 1.2192 2.1082)
			(stroke
				(width 0.1524)
				(type default)
			)
			(layer "B.SilkS")
		)
		(fp_line
			(start 1.2192 2.1082)
			(end 1.2192 -2.1082)
			(stroke
				(width 0.1524)
				(type default)
			)
			(layer "B.SilkS")
		)
		(fp_line
			(start -1.2192 0.813562)
			(end -1.2192 2.1082)
			(stroke
				(width 0.1524)
				(type default)
			)
			(layer "B.SilkS")
		)
		(fp_line
			(start -1.2192 -2.1082)
			(end -1.2192 -0.82677)
			(stroke
				(width 0.1524)
				(type default)
			)
			(layer "B.SilkS")
		)
		(fp_line
			(start 1.2192 -2.1082)
			(end -1.2192 -2.1082)
			(stroke
				(width 0.1524)
				(type default)
			)
			(layer "B.SilkS")
		)
		(pad "" np_thru_hole circle
			(at -3.4671 -1.27 180)
			(size 1.0414 1.0414)
			(drill 1.0414)
			(layers "*.Cu" "*.Mask")
			(clearance 0.381)
			(thermal_gap 0.381)
		)
		(pad "" np_thru_hole circle
			(at -3.4671 1.27 180)
			(size 1.0414 1.0414)
			(drill 1.0414)
			(layers "*.Cu" "*.Mask")
			(clearance 0.381)
			(thermal_gap 0.381)
		)
		(pad "" np_thru_hole circle
			(at 2.8829 -1.27 180)
			(size 1.0414 1.0414)
			(drill 1.0414)
			(layers "*.Cu" "*.Mask")
			(clearance 0.381)
			(thermal_gap 0.381)
		)
		(pad "" np_thru_hole circle
			(at 2.8829 1.27 180)
			(size 1.0414 1.0414)
			(drill 1.0414)
			(layers "*.Cu" "*.Mask")
			(clearance 0.381)
			(thermal_gap 0.381)
		)
		(pad "1" smd rect
			(at -0.8255 -0.249936 180)
			(size 0.3048 0.508)
			(layers "B.Cu" "B.Mask" "B.Paste")
			(net "85_5INCH_IN1_DP")
		)
		(pad "2" smd rect
			(at -0.8255 0.249936 180)
			(size 0.3048 0.508)
			(layers "B.Cu" "B.Mask" "B.Paste")
			(net "85_5INCH_IN1_DN")
		)
		(pad "3" smd circle
			(at 0 0 90)
			(size 0 0)
			(layers "B.Cu" "B.Mask" "B.Paste")
			(net "GND_P1")
		)
		(zone
			(layers "F.Cu" "B.Cu" "In1.Cu" "In2.Cu" "In3.Cu" "In4.Cu" "In5.Cu" "In6.Cu"
				"In7.Cu" "In8.Cu" "In9.Cu" "In10.Cu"
			)
			(hatch none 0.5)
			(connect_pads
				(clearance 0)
			)
			(min_thickness 0.25)
			(keepout
				(tracks not_allowed)
				(vias allowed)
				(pads allowed)
				(copperpour not_allowed)
				(footprints allowed)
			)
			(placement
				(enabled no)
				(sheetname "")
			)
			(fill
				(thermal_gap 0.5)
				(thermal_bridge_width 0.5)
				(island_removal_mode 0)
			)
			(polygon
				(pts
					(arc
						(start 95.568516 109.299502)
						(mid 93.714316 109.299502)
						(end 95.568516 109.299502)
					)
				)
			)
		)
		(zone
			(layers "F.Cu" "B.Cu" "In1.Cu" "In2.Cu" "In3.Cu" "In4.Cu" "In5.Cu" "In6.Cu"
				"In7.Cu" "In8.Cu" "In9.Cu" "In10.Cu"
			)
			(hatch none 0.5)
			(connect_pads
				(clearance 0)
			)
			(min_thickness 0.25)
			(keepout
				(tracks not_allowed)
				(vias allowed)
				(pads allowed)
				(copperpour not_allowed)
				(footprints allowed)
			)
			(placement
				(enabled no)
				(sheetname "")
			)
			(fill
				(thermal_gap 0.5)
				(thermal_bridge_width 0.5)
				(island_removal_mode 0)
			)
			(polygon
				(pts
					(arc
						(start 95.568516 115.649502)
						(mid 93.714316 115.649502)
						(end 95.568516 115.649502)
					)
				)
			)
		)
		(zone
			(layers "F.Cu" "B.Cu" "In1.Cu" "In2.Cu" "In3.Cu" "In4.Cu" "In5.Cu" "In6.Cu"
				"In7.Cu" "In8.Cu" "In9.Cu" "In10.Cu"
			)
			(hatch none 0.5)
			(connect_pads
				(clearance 0)
			)
			(min_thickness 0.25)
			(keepout
				(tracks not_allowed)
				(vias allowed)
				(pads allowed)
				(copperpour not_allowed)
				(footprints allowed)
			)
			(placement
				(enabled no)
				(sheetname "")
			)
			(fill
				(thermal_gap 0.5)
				(thermal_bridge_width 0.5)
				(island_removal_mode 0)
			)
			(polygon
				(pts
					(arc
						(start 98.108516 109.299502)
						(mid 96.254316 109.299502)
						(end 98.108516 109.299502)
					)
				)
			)
		)
		(zone
			(layers "F.Cu" "B.Cu" "In1.Cu" "In2.Cu" "In3.Cu" "In4.Cu" "In5.Cu" "In6.Cu"
				"In7.Cu" "In8.Cu" "In9.Cu" "In10.Cu"
			)
			(hatch none 0.5)
			(connect_pads
				(clearance 0)
			)
			(min_thickness 0.25)
			(keepout
				(tracks not_allowed)
				(vias allowed)
				(pads allowed)
				(copperpour not_allowed)
				(footprints allowed)
			)
			(placement
				(enabled no)
				(sheetname "")
			)
			(fill
				(thermal_gap 0.5)
				(thermal_bridge_width 0.5)
				(island_removal_mode 0)
			)
			(polygon
				(pts
					(arc
						(start 98.108516 115.649502)
						(mid 96.254316 115.649502)
						(end 98.108516 115.649502)
					)
				)
			)
		)
		(zone
			(layer "B.Cu")
			(hatch none 0.5)
			(connect_pads
				(clearance 0)
			)
			(min_thickness 0.25)
			(keepout
				(tracks not_allowed)
				(vias allowed)
				(pads allowed)
				(copperpour not_allowed)
				(footprints allowed)
			)
			(placement
				(enabled no)
				(sheetname "")
			)
			(fill
				(thermal_gap 0.5)
				(thermal_bridge_width 0.5)
				(island_removal_mode 0)
			)
			(polygon
				(pts
					(xy 96.460056 111.649002) (xy 96.364552 111.649002) (xy 96.364552 112.245902) (xy 95.958152 112.245902)
					(xy 95.958152 111.649002) (xy 95.86468 111.649002) (xy 95.86468 112.245902) (xy 95.45828 112.245902)
					(xy 95.45828 111.649002) (xy 95.362776 111.649002) (xy 95.362776 112.347502) (xy 96.460056 112.347502)
				)
			)
		)
	)
	(footprint ""
		(layer "B.Cu")
		(at 78.867 -29.718 -90)
		(property "Reference" "R698"
			(at 0 0 90)
			(layer "B.SilkS")
			(hide yes)
			(effects
				(font
					(size 1.27 1.27)
				)
				(justify mirror)
			)
		)
		(property "Value" ""
			(at 0 0 90)
			(layer "B.Fab")
			(effects
				(font
					(size 1.27 1.27)
				)
				(justify mirror)
			)
		)
		(duplicate_pad_numbers_are_jumpers no)
		(fp_line
			(start -0.7874 0.4064)
			(end 0.7874 0.4064)
			(stroke
				(width 0.1524)
				(type default)
			)
			(layer "B.SilkS")
		)
		(fp_line
			(start 0.7874 0.4064)
			(end 0.7874 -0.4064)
			(stroke
				(width 0.1524)
				(type default)
			)
			(layer "B.SilkS")
		)
		(fp_line
			(start -0.7874 -0.4064)
			(end -0.7874 0.4064)
			(stroke
				(width 0.1524)
				(type default)
			)
			(layer "B.SilkS")
		)
		(fp_line
			(start 0.7874 -0.4064)
			(end -0.7874 -0.4064)
			(stroke
				(width 0.1524)
				(type default)
			)
			(layer "B.SilkS")
		)
		(fp_line
			(start -0.67945 0.3048)
			(end -0.120396 0.3048)
			(stroke
				(width 0.1)
				(type default)
			)
			(layer "B.Fab")
		)
		(fp_line
			(start -0.120396 0.3048)
			(end -0.120396 0.2794)
			(stroke
				(width 0.1)
				(type default)
			)
			(layer "B.Fab")
		)
		(fp_line
			(start 0.12065 0.3048)
			(end 0.67945 0.3048)
			(stroke
				(width 0.1)
				(type default)
			)
			(layer "B.Fab")
		)
		(fp_line
			(start 0.67945 0.3048)
			(end 0.67945 -0.305054)
			(stroke
				(width 0.1)
				(type default)
			)
			(layer "B.Fab")
		)
		(fp_line
			(start -0.120396 0.2794)
			(end 0.12065 0.2794)
			(stroke
				(width 0.1)
				(type default)
			)
			(layer "B.Fab")
		)
		(fp_line
			(start 0.12065 0.2794)
			(end 0.12065 0.3048)
			(stroke
				(width 0.1)
				(type default)
			)
			(layer "B.Fab")
		)
		(fp_line
			(start -0.12065 -0.2794)
			(end -0.12065 -0.3048)
			(stroke
				(width 0.1)
				(type default)
			)
			(layer "B.Fab")
		)
		(fp_line
			(start 0.12065 -0.2794)
			(end -0.12065 -0.2794)
			(stroke
				(width 0.1)
				(type default)
			)
			(layer "B.Fab")
		)
		(fp_line
			(start -0.67945 -0.3048)
			(end -0.67945 0.3048)
			(stroke
				(width 0.1)
				(type default)
			)
			(layer "B.Fab")
		)
		(fp_line
			(start -0.12065 -0.3048)
			(end -0.67945 -0.3048)
			(stroke
				(width 0.1)
				(type default)
			)
			(layer "B.Fab")
		)
		(fp_line
			(start 0.12065 -0.305054)
			(end 0.12065 -0.2794)
			(stroke
				(width 0.1)
				(type default)
			)
			(layer "B.Fab")
		)
		(fp_line
			(start 0.67945 -0.305054)
			(end 0.12065 -0.305054)
			(stroke
				(width 0.1)
				(type default)
			)
			(layer "B.Fab")
		)
		(pad "1" smd circle
			(at 0.40005 0 90)
			(size 0 0)
			(layers "B.Cu" "B.Mask" "B.Paste")
			(net "LED_POSTCODE_1")
		)
		(pad "2" smd circle
			(at -0.40005 0 90)
			(size 0 0)
			(layers "B.Cu" "B.Mask" "B.Paste")
			(net "LED_POSTCODE_1_R1")
		)
	)
	(footprint ""
		(layer "B.Cu")
		(at 16.383 -17.907 -90)
		(property "Reference" "R409"
			(at 0 0 90)
			(layer "B.SilkS")
			(hide yes)
			(effects
				(font
					(size 1.27 1.27)
				)
				(justify mirror)
			)
		)
		(property "Value" ""
			(at 0 0 90)
			(layer "B.Fab")
			(effects
				(font
					(size 1.27 1.27)
				)
				(justify mirror)
			)
		)
		(duplicate_pad_numbers_are_jumpers no)
		(fp_line
			(start -0.7874 0.4064)
			(end 0.7874 0.4064)
			(stroke
				(width 0.1524)
				(type default)
			)
			(layer "B.SilkS")
		)
		(fp_line
			(start 0.7874 0.4064)
			(end 0.7874 -0.4064)
			(stroke
				(width 0.1524)
				(type default)
			)
			(layer "B.SilkS")
		)
		(fp_line
			(start -0.7874 -0.4064)
			(end -0.7874 0.4064)
			(stroke
				(width 0.1524)
				(type default)
			)
			(layer "B.SilkS")
		)
		(fp_line
			(start 0.7874 -0.4064)
			(end -0.7874 -0.4064)
			(stroke
				(width 0.1524)
				(type default)
			)
			(layer "B.SilkS")
		)
		(fp_line
			(start -0.67945 0.3048)
			(end -0.120396 0.3048)
			(stroke
				(width 0.1)
				(type default)
			)
			(layer "B.Fab")
		)
		(fp_line
			(start -0.120396 0.3048)
			(end -0.120396 0.2794)
			(stroke
				(width 0.1)
				(type default)
			)
			(layer "B.Fab")
		)
		(fp_line
			(start 0.12065 0.3048)
			(end 0.67945 0.3048)
			(stroke
				(width 0.1)
				(type default)
			)
			(layer "B.Fab")
		)
		(fp_line
			(start 0.67945 0.3048)
			(end 0.67945 -0.305054)
			(stroke
				(width 0.1)
				(type default)
			)
			(layer "B.Fab")
		)
		(fp_line
			(start -0.120396 0.2794)
			(end 0.12065 0.2794)
			(stroke
				(width 0.1)
				(type default)
			)
			(layer "B.Fab")
		)
		(fp_line
			(start 0.12065 0.2794)
			(end 0.12065 0.3048)
			(stroke
				(width 0.1)
				(type default)
			)
			(layer "B.Fab")
		)
		(fp_line
			(start -0.12065 -0.2794)
			(end -0.12065 -0.3048)
			(stroke
				(width 0.1)
				(type default)
			)
			(layer "B.Fab")
		)
		(fp_line
			(start 0.12065 -0.2794)
			(end -0.12065 -0.2794)
			(stroke
				(width 0.1)
				(type default)
			)
			(layer "B.Fab")
		)
		(fp_line
			(start -0.67945 -0.3048)
			(end -0.67945 0.3048)
			(stroke
				(width 0.1)
				(type default)
			)
			(layer "B.Fab")
		)
		(fp_line
			(start -0.12065 -0.3048)
			(end -0.67945 -0.3048)
			(stroke
				(width 0.1)
				(type default)
			)
			(layer "B.Fab")
		)
		(fp_line
			(start 0.12065 -0.305054)
			(end 0.12065 -0.2794)
			(stroke
				(width 0.1)
				(type default)
			)
			(layer "B.Fab")
		)
		(fp_line
			(start 0.67945 -0.305054)
			(end 0.12065 -0.305054)
			(stroke
				(width 0.1)
				(type default)
			)
			(layer "B.Fab")
		)
		(pad "1" smd circle
			(at 0.40005 0 90)
			(size 0 0)
			(layers "B.Cu" "B.Mask" "B.Paste")
			(net "SMB_TMP421_BMC_MM2_SDA")
		)
		(pad "2" smd circle
			(at -0.40005 0 90)
			(size 0 0)
			(layers "B.Cu" "B.Mask" "B.Paste")
			(net "SMB_BMC_MM2_SDA")
		)
	)
	(footprint ""
		(layer "B.Cu")
		(at 49.53 -34.671 -90)
		(property "Reference" "R153"
			(at 0 0 90)
			(layer "B.SilkS")
			(hide yes)
			(effects
				(font
					(size 1.27 1.27)
				)
				(justify mirror)
			)
		)
		(property "Value" ""
			(at 0 0 90)
			(layer "B.Fab")
			(effects
				(font
					(size 1.27 1.27)
				)
				(justify mirror)
			)
		)
		(duplicate_pad_numbers_are_jumpers no)
		(fp_line
			(start -0.7874 0.4064)
			(end 0.7874 0.4064)
			(stroke
				(width 0.1524)
				(type default)
			)
			(layer "B.SilkS")
		)
		(fp_line
			(start 0.7874 0.4064)
			(end 0.7874 -0.4064)
			(stroke
				(width 0.1524)
				(type default)
			)
			(layer "B.SilkS")
		)
		(fp_line
			(start -0.7874 -0.4064)
			(end -0.7874 0.4064)
			(stroke
				(width 0.1524)
				(type default)
			)
			(layer "B.SilkS")
		)
		(fp_line
			(start 0.7874 -0.4064)
			(end -0.7874 -0.4064)
			(stroke
				(width 0.1524)
				(type default)
			)
			(layer "B.SilkS")
		)
		(fp_line
			(start -0.67945 0.3048)
			(end -0.120396 0.3048)
			(stroke
				(width 0.1)
				(type default)
			)
			(layer "B.Fab")
		)
		(fp_line
			(start -0.120396 0.3048)
			(end -0.120396 0.2794)
			(stroke
				(width 0.1)
				(type default)
			)
			(layer "B.Fab")
		)
		(fp_line
			(start 0.12065 0.3048)
			(end 0.67945 0.3048)
			(stroke
				(width 0.1)
				(type default)
			)
			(layer "B.Fab")
		)
		(fp_line
			(start 0.67945 0.3048)
			(end 0.67945 -0.305054)
			(stroke
				(width 0.1)
				(type default)
			)
			(layer "B.Fab")
		)
		(fp_line
			(start -0.120396 0.2794)
			(end 0.12065 0.2794)
			(stroke
				(width 0.1)
				(type default)
			)
			(layer "B.Fab")
		)
		(fp_line
			(start 0.12065 0.2794)
			(end 0.12065 0.3048)
			(stroke
				(width 0.1)
				(type default)
			)
			(layer "B.Fab")
		)
		(fp_line
			(start -0.12065 -0.2794)
			(end -0.12065 -0.3048)
			(stroke
				(width 0.1)
				(type default)
			)
			(layer "B.Fab")
		)
		(fp_line
			(start 0.12065 -0.2794)
			(end -0.12065 -0.2794)
			(stroke
				(width 0.1)
				(type default)
			)
			(layer "B.Fab")
		)
		(fp_line
			(start -0.67945 -0.3048)
			(end -0.67945 0.3048)
			(stroke
				(width 0.1)
				(type default)
			)
			(layer "B.Fab")
		)
		(fp_line
			(start -0.12065 -0.3048)
			(end -0.67945 -0.3048)
			(stroke
				(width 0.1)
				(type default)
			)
			(layer "B.Fab")
		)
		(fp_line
			(start 0.12065 -0.305054)
			(end 0.12065 -0.2794)
			(stroke
				(width 0.1)
				(type default)
			)
			(layer "B.Fab")
		)
		(fp_line
			(start 0.67945 -0.305054)
			(end 0.12065 -0.305054)
			(stroke
				(width 0.1)
				(type default)
			)
			(layer "B.Fab")
		)
		(pad "1" smd circle
			(at 0.40005 0 90)
			(size 0 0)
			(layers "B.Cu" "B.Mask" "B.Paste")
			(net "SMB_BMC_MM16_SDA")
		)
		(pad "2" smd circle
			(at -0.40005 0 90)
			(size 0 0)
			(layers "B.Cu" "B.Mask" "B.Paste")
			(net "SMB_BMC_MM16_R_SDA")
		)
	)
	(footprint ""
		(layer "B.Cu")
		(at 67.529964 -37.0205 -90)
		(property "Reference" "C46"
			(at 0 0 90)
			(layer "B.SilkS")
			(hide yes)
			(effects
				(font
					(size 1.27 1.27)
				)
				(justify mirror)
			)
		)
		(property "Value" ""
			(at 0 0 90)
			(layer "B.Fab")
			(effects
				(font
					(size 1.27 1.27)
				)
				(justify mirror)
			)
		)
		(duplicate_pad_numbers_are_jumpers no)
		(fp_line
			(start -0.7874 0.4064)
			(end 0.7874 0.4064)
			(stroke
				(width 0.1524)
				(type default)
			)
			(layer "B.SilkS")
		)
		(fp_line
			(start 0.7874 0.4064)
			(end 0.7874 -0.4064)
			(stroke
				(width 0.1524)
				(type default)
			)
			(layer "B.SilkS")
		)
		(fp_line
			(start -0.7874 -0.4064)
			(end -0.7874 0.4064)
			(stroke
				(width 0.1524)
				(type default)
			)
			(layer "B.SilkS")
		)
		(fp_line
			(start 0.7874 -0.4064)
			(end -0.7874 -0.4064)
			(stroke
				(width 0.1524)
				(type default)
			)
			(layer "B.SilkS")
		)
		(fp_line
			(start -0.67945 0.3048)
			(end -0.120396 0.3048)
			(stroke
				(width 0.1)
				(type default)
			)
			(layer "B.Fab")
		)
		(fp_line
			(start -0.120396 0.3048)
			(end -0.120396 0.2794)
			(stroke
				(width 0.1)
				(type default)
			)
			(layer "B.Fab")
		)
		(fp_line
			(start 0.12065 0.3048)
			(end 0.67945 0.3048)
			(stroke
				(width 0.1)
				(type default)
			)
			(layer "B.Fab")
		)
		(fp_line
			(start 0.67945 0.3048)
			(end 0.67945 -0.305054)
			(stroke
				(width 0.1)
				(type default)
			)
			(layer "B.Fab")
		)
		(fp_line
			(start -0.120396 0.2794)
			(end 0.12065 0.2794)
			(stroke
				(width 0.1)
				(type default)
			)
			(layer "B.Fab")
		)
		(fp_line
			(start 0.12065 0.2794)
			(end 0.12065 0.3048)
			(stroke
				(width 0.1)
				(type default)
			)
			(layer "B.Fab")
		)
		(fp_line
			(start -0.12065 -0.2794)
			(end -0.12065 -0.3048)
			(stroke
				(width 0.1)
				(type default)
			)
			(layer "B.Fab")
		)
		(fp_line
			(start 0.12065 -0.2794)
			(end -0.12065 -0.2794)
			(stroke
				(width 0.1)
				(type default)
			)
			(layer "B.Fab")
		)
		(fp_line
			(start -0.67945 -0.3048)
			(end -0.67945 0.3048)
			(stroke
				(width 0.1)
				(type default)
			)
			(layer "B.Fab")
		)
		(fp_line
			(start -0.12065 -0.3048)
			(end -0.67945 -0.3048)
			(stroke
				(width 0.1)
				(type default)
			)
			(layer "B.Fab")
		)
		(fp_line
			(start 0.12065 -0.305054)
			(end 0.12065 -0.2794)
			(stroke
				(width 0.1)
				(type default)
			)
			(layer "B.Fab")
		)
		(fp_line
			(start 0.67945 -0.305054)
			(end 0.12065 -0.305054)
			(stroke
				(width 0.1)
				(type default)
			)
			(layer "B.Fab")
		)
		(pad "1" smd circle
			(at 0.40005 0 90)
			(size 0 0)
			(layers "B.Cu" "B.Mask" "B.Paste")
			(net "P1V8_STBY_AVDDPLL")
		)
		(pad "2" smd circle
			(at -0.40005 0 90)
			(size 0 0)
			(layers "B.Cu" "B.Mask" "B.Paste")
			(net "GND")
		)
	)
)
